(kicad_pcb
	(version 20260206)
	(generator "pcbnew")
	(generator_version "10.0")
	(general
		(thickness 1.6)
		(legacy_teardrops no)
	)
	(paper "A4")
	(title_block
		(title "Wiwynn_Tioga_Pass_MB.brd")
		(comment 1 "Tioga Pass / footprints 4511-4517 of 4770")
	)
	(layers
		(0 "F.Cu" signal "TOP")
		(4 "In1.Cu" signal "L2GND")
		(6 "In2.Cu" signal "L3")
		(8 "In3.Cu" signal "L4GND")
		(10 "In4.Cu" signal "L5")
		(12 "In5.Cu" signal "L6GND")
		(14 "In6.Cu" signal "L7VCC")
		(16 "In7.Cu" signal "L8VCC")
		(18 "In8.Cu" signal "L9GND")
		(20 "In9.Cu" signal "L10")
		(22 "In10.Cu" signal "L11GND")
		(24 "In11.Cu" signal "L12")
		(26 "In12.Cu" signal "L13GND")
		(2 "B.Cu" signal "BOTTOM")
		(9 "F.Adhes" user "F.Adhesive")
		(11 "B.Adhes" user "B.Adhesive")
		(13 "F.Paste" user "Package Geometry/Pastemask Top")
		(15 "B.Paste" user "Package Geometry/Pastemask Bottom")
		(5 "F.SilkS" user "Ref Des/Silkscreen Top")
		(7 "B.SilkS" user "Ref Des/Silkscreen Bottom")
		(1 "F.Mask" user "Board Geometry/Soldermask Top")
		(3 "B.Mask" user "Board Geometry/Soldermask Bottom")
		(17 "Dwgs.User" user "User.Drawings")
		(19 "Cmts.User" user "User.Comments")
		(21 "Eco1.User" user "User.Eco1")
		(23 "Eco2.User" user "User.Eco2")
		(25 "Edge.Cuts" user "Board Geometry/Outline")
		(27 "Margin" user)
		(31 "F.CrtYd" user "Package Geometry/Place Bound Top")
		(29 "B.CrtYd" user "Package Geometry/Place Bound Bottom")
		(35 "F.Fab" user "Ref Des/Assembly Top")
		(33 "B.Fab" user "Ref Des/Assembly Bottom")
	)
	(footprint ""
		(layer "B.Cu")
		(at 310.307228 -28.944824)
		(property "Reference" "R8D31"
			(at 0 0 0)
			(layer "B.SilkS")
			(hide yes)
			(effects
				(font
					(size 1.27 1.27)
				)
				(justify mirror)
			)
		)
		(property "Value" ""
			(at 0 0 0)
			(layer "B.Fab")
			(effects
				(font
					(size 1.27 1.27)
				)
				(justify mirror)
			)
		)
		(duplicate_pad_numbers_are_jumpers no)
		(fp_poly
			(pts
				(xy 0.2794 -0.1016) (xy -0.2794 -0.1016) (xy -0.2794 0.9906) (xy 0.2794 0.9906)
			)
			(stroke
				(width 0)
				(type default)
			)
			(fill no)
			(layer "B.CrtYd")
		)
		(fp_line
			(start -0.2794 -0.1016)
			(end 0.2794 -0.1016)
			(stroke
				(width 0.1)
				(type default)
			)
			(layer "B.Fab")
		)
		(fp_line
			(start -0.2794 0.9906)
			(end -0.2794 -0.1016)
			(stroke
				(width 0.1)
				(type default)
			)
			(layer "B.Fab")
		)
		(fp_line
			(start 0.2794 -0.1016)
			(end 0.2794 0.9906)
			(stroke
				(width 0.1)
				(type default)
			)
			(layer "B.Fab")
		)
		(fp_line
			(start 0.2794 0.9906)
			(end -0.2794 0.9906)
			(stroke
				(width 0.1)
				(type default)
			)
			(layer "B.Fab")
		)
		(pad "1" smd rect
			(at 0 0 180)
			(size 0.508 0.508)
			(layers "B.Cu" "B.Mask" "B.Paste")
			(net "P3V3_STBY")
		)
		(pad "2" smd rect
			(at 0 0.889 180)
			(size 0.508 0.508)
			(layers "B.Cu" "B.Mask" "B.Paste")
			(net "IRQ_DIMM_SAVE_LVT3_N")
		)
		(zone
			(layer "B.Cu")
			(hatch none 0.5)
			(connect_pads
				(clearance 0)
			)
			(min_thickness 0.25)
			(keepout
				(tracks allowed)
				(vias not_allowed)
				(pads allowed)
				(copperpour not_allowed)
				(footprints allowed)
			)
			(placement
				(enabled no)
				(sheetname "")
			)
			(fill
				(thermal_gap 0.5)
				(thermal_bridge_width 0.5)
				(island_removal_mode 0)
			)
			(polygon
				(pts
					(xy 310.561228 -28.690824) (xy 310.053228 -28.690824) (xy 310.053228 -28.309824) (xy 310.561228 -28.309824)
				)
			)
		)
		(zone
			(layer "B.Cu")
			(hatch none 0.5)
			(connect_pads
				(clearance 0)
			)
			(min_thickness 0.25)
			(keepout
				(tracks not_allowed)
				(vias allowed)
				(pads allowed)
				(copperpour not_allowed)
				(footprints allowed)
			)
			(placement
				(enabled no)
				(sheetname "")
			)
			(fill
				(thermal_gap 0.5)
				(thermal_bridge_width 0.5)
				(island_removal_mode 0)
			)
			(polygon
				(pts
					(xy 310.561228 -28.309824) (xy 310.053228 -28.309824) (xy 310.053228 -28.690824) (xy 310.561228 -28.690824)
				)
			)
		)
	)
	(footprint ""
		(layer "B.Cu")
		(at 13.11402 -99.57308 90)
		(property "Reference" "C9N16"
			(at 0 0 90)
			(layer "B.SilkS")
			(hide yes)
			(effects
				(font
					(size 1.27 1.27)
				)
				(justify mirror)
			)
		)
		(property "Value" ""
			(at 0 0 90)
			(layer "B.Fab")
			(effects
				(font
					(size 1.27 1.27)
				)
				(justify mirror)
			)
		)
		(duplicate_pad_numbers_are_jumpers no)
		(fp_poly
			(pts
				(xy -0.3048 -0.1016) (xy -0.3048 0.9906) (xy 0.3048 0.9906) (xy 0.3048 -0.1016)
			)
			(stroke
				(width 0)
				(type default)
			)
			(fill no)
			(layer "B.CrtYd")
		)
		(fp_line
			(start 0.3048 -0.1016)
			(end 0.3048 0.9906)
			(stroke
				(width 0.1)
				(type default)
			)
			(layer "B.Fab")
		)
		(fp_line
			(start -0.3048 -0.1016)
			(end 0.3048 -0.1016)
			(stroke
				(width 0.1)
				(type default)
			)
			(layer "B.Fab")
		)
		(fp_line
			(start 0.3048 0.9906)
			(end -0.3048 0.9906)
			(stroke
				(width 0.1)
				(type default)
			)
			(layer "B.Fab")
		)
		(fp_line
			(start -0.3048 0.9906)
			(end -0.3048 -0.1016)
			(stroke
				(width 0.1)
				(type default)
			)
			(layer "B.Fab")
		)
		(pad "1" smd rect
			(at 0 0 270)
			(size 0.508 0.508)
			(layers "B.Cu" "B.Mask" "B.Paste")
			(net "P3E_CPU1_PE3_MP_C_TXN<12>")
		)
		(pad "2" smd rect
			(at 0 0.889 270)
			(size 0.508 0.508)
			(layers "B.Cu" "B.Mask" "B.Paste")
			(net "P3E_CPU1_PE3_MP_TXN<12>")
		)
		(zone
			(layer "B.Cu")
			(hatch none 0.5)
			(connect_pads
				(clearance 0)
			)
			(min_thickness 0.25)
			(keepout
				(tracks allowed)
				(vias not_allowed)
				(pads allowed)
				(copperpour not_allowed)
				(footprints allowed)
			)
			(placement
				(enabled no)
				(sheetname "")
			)
			(fill
				(thermal_gap 0.5)
				(thermal_bridge_width 0.5)
				(island_removal_mode 0)
			)
			(polygon
				(pts
					(xy 13.36802 -99.82708) (xy 13.36802 -99.31908) (xy 13.74902 -99.31908) (xy 13.74902 -99.82708)
				)
			)
		)
		(zone
			(layer "B.Cu")
			(hatch none 0.5)
			(connect_pads
				(clearance 0)
			)
			(min_thickness 0.25)
			(keepout
				(tracks not_allowed)
				(vias allowed)
				(pads allowed)
				(copperpour not_allowed)
				(footprints allowed)
			)
			(placement
				(enabled no)
				(sheetname "")
			)
			(fill
				(thermal_gap 0.5)
				(thermal_bridge_width 0.5)
				(island_removal_mode 0)
			)
			(polygon
				(pts
					(xy 13.74902 -99.82708) (xy 13.74902 -99.31908) (xy 13.36802 -99.31908) (xy 13.36802 -99.82708)
				)
			)
		)
	)
	(footprint ""
		(layer "B.Cu")
		(at 374.231916 -37.063426 180)
		(property "Reference" "Q7E5"
			(at -2.94005 3.6957 90)
			(unlocked yes)
			(layer "B.SilkS")
			(effects
				(font
					(size 0.7874 0.5842)
					(thickness 0.1524)
				)
				(justify left mirror)
			)
		)
		(property "Value" ""
			(at 0 0 0)
			(layer "B.Fab")
			(effects
				(font
					(size 1.27 1.27)
				)
				(justify mirror)
			)
		)
		(duplicate_pad_numbers_are_jumpers no)
		(fp_circle
			(center 0.784352 -0.400558)
			(end 0.657352 -0.400558)
			(stroke
				(width 0.254)
				(type default)
			)
			(fill no)
			(layer "B.SilkS")
		)
		(fp_poly
			(pts
				(xy -0.2159 1.7526) (xy -1.5621 1.7526) (xy -1.5621 -0.4572) (xy -0.2159 -0.4572)
			)
			(stroke
				(width 0)
				(type default)
			)
			(fill no)
			(layer "B.CrtYd")
		)
		(fp_line
			(start -0.2159 1.75514)
			(end -1.5621 1.75514)
			(stroke
				(width 0.1)
				(type default)
			)
			(layer "B.Fab")
		)
		(fp_line
			(start -0.2159 -0.45466)
			(end -0.2159 1.75514)
			(stroke
				(width 0.1)
				(type default)
			)
			(layer "B.Fab")
		)
		(fp_line
			(start -1.5621 1.75514)
			(end -1.5621 -0.45466)
			(stroke
				(width 0.1)
				(type default)
			)
			(layer "B.Fab")
		)
		(fp_line
			(start -1.5621 -0.45466)
			(end -0.2159 -0.45466)
			(stroke
				(width 0.1)
				(type default)
			)
			(layer "B.Fab")
		)
		(fp_circle
			(center 0.508 -0.7874)
			(end 0.381 -0.7874)
			(stroke
				(width 0.254)
				(type default)
			)
			(fill no)
			(layer "B.Fab")
		)
		(pad "1" smd rect
			(at 0 0)
			(size 1.016 0.381)
			(layers "B.Cu" "B.Mask" "B.Paste")
			(net "GND")
		)
		(pad "2" smd rect
			(at 0 0.65024)
			(size 1.016 0.381)
			(layers "B.Cu" "B.Mask" "B.Paste")
			(net "IRQ_CPU0_PROCHOT_G_N")
		)
		(pad "3" smd rect
			(at 0 1.30048)
			(size 1.016 0.381)
			(layers "B.Cu" "B.Mask" "B.Paste")
			(net "H_CPU0_PROCHOT_G_N")
		)
		(pad "4" smd rect
			(at -1.778 1.30048)
			(size 1.016 0.381)
			(layers "B.Cu" "B.Mask" "B.Paste")
			(net "GND")
		)
		(pad "5" smd rect
			(at -1.778 0.65024)
			(size 1.016 0.381)
			(layers "B.Cu" "B.Mask" "B.Paste")
			(net "IRQ_CPU0_VRHOT")
		)
		(pad "6" smd rect
			(at -1.778 0)
			(size 1.016 0.381)
			(layers "B.Cu" "B.Mask" "B.Paste")
			(net "IRQ_CPU0_VRHOT")
		)
		(zone
			(layer "B.Cu")
			(hatch none 0.5)
			(connect_pads
				(clearance 0)
			)
			(min_thickness 0.25)
			(keepout
				(tracks allowed)
				(vias not_allowed)
				(pads allowed)
				(copperpour not_allowed)
				(footprints allowed)
			)
			(placement
				(enabled no)
				(sheetname "")
			)
			(fill
				(thermal_gap 0.5)
				(thermal_bridge_width 0.5)
				(island_removal_mode 0)
			)
			(polygon
				(pts
					(xy 373.723916 -36.872926) (xy 374.739916 -36.872926) (xy 374.739916 -38.562026) (xy 373.723916 -38.562026)
				)
			)
		)
		(zone
			(layer "B.Cu")
			(hatch none 0.5)
			(connect_pads
				(clearance 0)
			)
			(min_thickness 0.25)
			(keepout
				(tracks allowed)
				(vias not_allowed)
				(pads allowed)
				(copperpour not_allowed)
				(footprints allowed)
			)
			(placement
				(enabled no)
				(sheetname "")
			)
			(fill
				(thermal_gap 0.5)
				(thermal_bridge_width 0.5)
				(island_removal_mode 0)
			)
			(polygon
				(pts
					(xy 375.501916 -36.872926) (xy 376.517916 -36.872926) (xy 376.517916 -38.562026) (xy 375.501916 -38.562026)
				)
			)
		)
	)
	(footprint ""
		(layer "B.Cu")
		(at 468.181944 -11.42492)
		(property "Reference" "R2U32"
			(at 0 0 0)
			(layer "B.SilkS")
			(hide yes)
			(effects
				(font
					(size 1.27 1.27)
				)
				(justify mirror)
			)
		)
		(property "Value" ""
			(at 0 0 0)
			(layer "B.Fab")
			(effects
				(font
					(size 1.27 1.27)
				)
				(justify mirror)
			)
		)
		(duplicate_pad_numbers_are_jumpers no)
		(fp_poly
			(pts
				(xy 0.2794 -0.1016) (xy -0.2794 -0.1016) (xy -0.2794 0.9906) (xy 0.2794 0.9906)
			)
			(stroke
				(width 0)
				(type default)
			)
			(fill no)
			(layer "B.CrtYd")
		)
		(fp_line
			(start -0.2794 -0.1016)
			(end 0.2794 -0.1016)
			(stroke
				(width 0.1)
				(type default)
			)
			(layer "B.Fab")
		)
		(fp_line
			(start -0.2794 0.9906)
			(end -0.2794 -0.1016)
			(stroke
				(width 0.1)
				(type default)
			)
			(layer "B.Fab")
		)
		(fp_line
			(start 0.2794 -0.1016)
			(end 0.2794 0.9906)
			(stroke
				(width 0.1)
				(type default)
			)
			(layer "B.Fab")
		)
		(fp_line
			(start 0.2794 0.9906)
			(end -0.2794 0.9906)
			(stroke
				(width 0.1)
				(type default)
			)
			(layer "B.Fab")
		)
		(pad "1" smd rect
			(at 0 0 180)
			(size 0.508 0.508)
			(layers "B.Cu" "B.Mask" "B.Paste")
			(net "SMB_SLOTX24_BMC_STBY_LVC3_SCL")
		)
		(pad "2" smd rect
			(at 0 0.889 180)
			(size 0.508 0.508)
			(layers "B.Cu" "B.Mask" "B.Paste")
			(net "SMB_SLOTX24_STBY_LVC3_SCL_R2")
		)
		(zone
			(layer "B.Cu")
			(hatch none 0.5)
			(connect_pads
				(clearance 0)
			)
			(min_thickness 0.25)
			(keepout
				(tracks allowed)
				(vias not_allowed)
				(pads allowed)
				(copperpour not_allowed)
				(footprints allowed)
			)
			(placement
				(enabled no)
				(sheetname "")
			)
			(fill
				(thermal_gap 0.5)
				(thermal_bridge_width 0.5)
				(island_removal_mode 0)
			)
			(polygon
				(pts
					(xy 468.435944 -11.17092) (xy 467.927944 -11.17092) (xy 467.927944 -10.78992) (xy 468.435944 -10.78992)
				)
			)
		)
		(zone
			(layer "B.Cu")
			(hatch none 0.5)
			(connect_pads
				(clearance 0)
			)
			(min_thickness 0.25)
			(keepout
				(tracks not_allowed)
				(vias allowed)
				(pads allowed)
				(copperpour not_allowed)
				(footprints allowed)
			)
			(placement
				(enabled no)
				(sheetname "")
			)
			(fill
				(thermal_gap 0.5)
				(thermal_bridge_width 0.5)
				(island_removal_mode 0)
			)
			(polygon
				(pts
					(xy 468.435944 -10.78992) (xy 467.927944 -10.78992) (xy 467.927944 -11.17092) (xy 468.435944 -11.17092)
				)
			)
		)
	)
	(footprint ""
		(layer "B.Cu")
		(at 365.379 -40.5892 180)
		(property "Reference" "C8F4"
			(at 0 0 0)
			(layer "B.SilkS")
			(hide yes)
			(effects
				(font
					(size 1.27 1.27)
				)
				(justify mirror)
			)
		)
		(property "Value" ""
			(at 0 0 0)
			(layer "B.Fab")
			(effects
				(font
					(size 1.27 1.27)
				)
				(justify mirror)
			)
		)
		(duplicate_pad_numbers_are_jumpers no)
		(fp_poly
			(pts
				(xy -0.3048 -0.1016) (xy -0.3048 0.9906) (xy 0.3048 0.9906) (xy 0.3048 -0.1016)
			)
			(stroke
				(width 0)
				(type default)
			)
			(fill no)
			(layer "B.CrtYd")
		)
		(fp_line
			(start 0.3048 0.9906)
			(end -0.3048 0.9906)
			(stroke
				(width 0.1)
				(type default)
			)
			(layer "B.Fab")
		)
		(fp_line
			(start 0.3048 -0.1016)
			(end 0.3048 0.9906)
			(stroke
				(width 0.1)
				(type default)
			)
			(layer "B.Fab")
		)
		(fp_line
			(start -0.3048 0.9906)
			(end -0.3048 -0.1016)
			(stroke
				(width 0.1)
				(type default)
			)
			(layer "B.Fab")
		)
		(fp_line
			(start -0.3048 -0.1016)
			(end 0.3048 -0.1016)
			(stroke
				(width 0.1)
				(type default)
			)
			(layer "B.Fab")
		)
		(pad "1" smd rect
			(at 0 0)
			(size 0.508 0.508)
			(layers "B.Cu" "B.Mask" "B.Paste")
			(net "P3V3_STBY")
		)
		(pad "2" smd rect
			(at 0 0.889)
			(size 0.508 0.508)
			(layers "B.Cu" "B.Mask" "B.Paste")
			(net "GND")
		)
		(zone
			(layer "B.Cu")
			(hatch none 0.5)
			(connect_pads
				(clearance 0)
			)
			(min_thickness 0.25)
			(keepout
				(tracks not_allowed)
				(vias allowed)
				(pads allowed)
				(copperpour not_allowed)
				(footprints allowed)
			)
			(placement
				(enabled no)
				(sheetname "")
			)
			(fill
				(thermal_gap 0.5)
				(thermal_bridge_width 0.5)
				(island_removal_mode 0)
			)
			(polygon
				(pts
					(xy 365.125 -41.2242) (xy 365.633 -41.2242) (xy 365.633 -40.8432) (xy 365.125 -40.8432)
				)
			)
		)
		(zone
			(layer "B.Cu")
			(hatch none 0.5)
			(connect_pads
				(clearance 0)
			)
			(min_thickness 0.25)
			(keepout
				(tracks allowed)
				(vias not_allowed)
				(pads allowed)
				(copperpour not_allowed)
				(footprints allowed)
			)
			(placement
				(enabled no)
				(sheetname "")
			)
			(fill
				(thermal_gap 0.5)
				(thermal_bridge_width 0.5)
				(island_removal_mode 0)
			)
			(polygon
				(pts
					(xy 365.125 -40.8432) (xy 365.633 -40.8432) (xy 365.633 -41.2242) (xy 365.125 -41.2242)
				)
			)
		)
	)
	(footprint ""
		(layer "B.Cu")
		(at 210.612228 -95.596202 -90)
		(property "Reference" "C6N4"
			(at -3.401568 -4.525772 0)
			(unlocked yes)
			(layer "B.SilkS")
			(effects
				(font
					(size 0.7874 0.5842)
					(thickness 0.1524)
				)
				(justify mirror)
			)
		)
		(property "Value" ""
			(at 0 0 90)
			(layer "B.Fab")
			(effects
				(font
					(size 1.27 1.27)
				)
				(justify mirror)
			)
		)
		(duplicate_pad_numbers_are_jumpers no)
		(fp_line
			(start -2.286 7.366)
			(end -1.600708 7.366)
			(stroke
				(width 0.1524)
				(type default)
			)
			(layer "B.SilkS")
		)
		(fp_line
			(start -2.286 7.366)
			(end -2.286 1.63195)
			(stroke
				(width 0.1524)
				(type default)
			)
			(layer "B.SilkS")
		)
		(fp_line
			(start 2.286 7.366)
			(end 1.60147 7.366)
			(stroke
				(width 0.1524)
				(type default)
			)
			(layer "B.SilkS")
		)
		(fp_line
			(start 2.286 7.366)
			(end 2.286 1.632712)
			(stroke
				(width 0.1524)
				(type default)
			)
			(layer "B.SilkS")
		)
		(fp_line
			(start -2.504948 1.633728)
			(end -1.6002 1.633728)
			(stroke
				(width 0.1524)
				(type default)
			)
			(layer "B.SilkS")
		)
		(fp_line
			(start 2.563114 1.633728)
			(end 1.6002 1.633728)
			(stroke
				(width 0.1524)
				(type default)
			)
			(layer "B.SilkS")
		)
		(fp_line
			(start -2.504948 -1.616456)
			(end -2.504948 1.633728)
			(stroke
				(width 0.1524)
				(type default)
			)
			(layer "B.SilkS")
		)
		(fp_line
			(start -1.6002 -1.616456)
			(end -2.504948 -1.616456)
			(stroke
				(width 0.1524)
				(type default)
			)
			(layer "B.SilkS")
		)
		(fp_line
			(start 1.6002 -1.616456)
			(end 2.563114 -1.616456)
			(stroke
				(width 0.1524)
				(type default)
			)
			(layer "B.SilkS")
		)
		(fp_line
			(start 2.563114 -1.616456)
			(end 2.563114 1.633728)
			(stroke
				(width 0.1524)
				(type default)
			)
			(layer "B.SilkS")
		)
		(fp_rect
			(start 2.286 7.366)
			(end -2.286 -0.254)
			(stroke
				(width 0)
				(type default)
			)
			(fill no)
			(layer "B.CrtYd")
		)
		(fp_line
			(start -2.286 7.366)
			(end 2.286 7.366)
			(stroke
				(width 0.1)
				(type default)
			)
			(layer "B.Fab")
		)
		(fp_line
			(start 2.286 7.366)
			(end 2.286 -0.254)
			(stroke
				(width 0.1)
				(type default)
			)
			(layer "B.Fab")
		)
		(fp_line
			(start -2.286 -0.254)
			(end -2.286 7.366)
			(stroke
				(width 0.1)
				(type default)
			)
			(layer "B.Fab")
		)
		(fp_line
			(start 2.286 -0.254)
			(end -2.286 -0.254)
			(stroke
				(width 0.1)
				(type default)
			)
			(layer "B.Fab")
		)
		(pad "1" smd rect
			(at 0 0 90)
			(size 2.54 3.048)
			(layers "B.Cu" "B.Mask" "B.Paste")
			(net "PVSA_CPU0")
		)
		(pad "2" smd rect
			(at 0 7.112 90)
			(size 2.54 3.048)
			(layers "B.Cu" "B.Mask" "B.Paste")
			(net "GND")
		)
	)
	(footprint ""
		(layer "B.Cu")
		(at 245.14302 -87.46236 -90)
		(property "Reference" "R5P2"
			(at 0 0 90)
			(layer "B.SilkS")
			(hide yes)
			(effects
				(font
					(size 1.27 1.27)
				)
				(justify mirror)
			)
		)
		(property "Value" ""
			(at 0 0 90)
			(layer "B.Fab")
			(effects
				(font
					(size 1.27 1.27)
				)
				(justify mirror)
			)
		)
		(duplicate_pad_numbers_are_jumpers no)
		(fp_poly
			(pts
				(xy 0.2794 -0.1016) (xy -0.2794 -0.1016) (xy -0.2794 0.9906) (xy 0.2794 0.9906)
			)
			(stroke
				(width 0)
				(type default)
			)
			(fill no)
			(layer "B.CrtYd")
		)
		(fp_line
			(start -0.2794 0.9906)
			(end -0.2794 -0.1016)
			(stroke
				(width 0.1)
				(type default)
			)
			(layer "B.Fab")
		)
		(fp_line
			(start 0.2794 0.9906)
			(end -0.2794 0.9906)
			(stroke
				(width 0.1)
				(type default)
			)
			(layer "B.Fab")
		)
		(fp_line
			(start -0.2794 -0.1016)
			(end 0.2794 -0.1016)
			(stroke
				(width 0.1)
				(type default)
			)
			(layer "B.Fab")
		)
		(fp_line
			(start 0.2794 -0.1016)
			(end 0.2794 0.9906)
			(stroke
				(width 0.1)
				(type default)
			)
			(layer "B.Fab")
		)
		(pad "1" smd rect
			(at 0 0 90)
			(size 0.508 0.508)
			(layers "B.Cu" "B.Mask" "B.Paste")
			(net "PD_CPU0_TEST14")
		)
		(pad "2" smd rect
			(at 0 0.889 90)
			(size 0.508 0.508)
			(layers "B.Cu" "B.Mask" "B.Paste")
			(net "GND")
		)
		(zone
			(layer "B.Cu")
			(hatch none 0.5)
			(connect_pads
				(clearance 0)
			)
			(min_thickness 0.25)
			(keepout
				(tracks not_allowed)
				(vias allowed)
				(pads allowed)
				(copperpour not_allowed)
				(footprints allowed)
			)
			(placement
				(enabled no)
				(sheetname "")
			)
			(fill
				(thermal_gap 0.5)
				(thermal_bridge_width 0.5)
				(island_removal_mode 0)
			)
			(polygon
				(pts
					(xy 244.50802 -87.20836) (xy 244.50802 -87.71636) (xy 244.88902 -87.71636) (xy 244.88902 -87.20836)
				)
			)
		)
		(zone
			(layer "B.Cu")
			(hatch none 0.5)
			(connect_pads
				(clearance 0)
			)
			(min_thickness 0.25)
			(keepout
				(tracks allowed)
				(vias not_allowed)
				(pads allowed)
				(copperpour not_allowed)
				(footprints allowed)
			)
			(placement
				(enabled no)
				(sheetname "")
			)
			(fill
				(thermal_gap 0.5)
				(thermal_bridge_width 0.5)
				(island_removal_mode 0)
			)
			(polygon
				(pts
					(xy 244.88902 -87.20836) (xy 244.88902 -87.71636) (xy 244.50802 -87.71636) (xy 244.50802 -87.20836)
				)
			)
		)
	)
)
